# S9S_MB_2U (Grand Teton) — schematic netlist excerpt (pin names and nets, part order shuffled) for the footprints in the layout excerpt that follows; sources: Cadence DE-HDL packaged netlist, KiCad conversion of 03242023_DA0F0TMBIJ0_F0T_Motherboard_J_brd_V01_OCP.brd

PC2189  Q_CAP  0.01UF 50V 10% X7R  pkg C0402  page 301 : A = HSC_VSENSE ; B = AGND_HSC
R4135  Q_RES  10K 1% CHIP  pkg 0402LF  page 146 : A = P3V3_AUX ; B = PRSNT_CABLE_GPU_A2_N

(kicad_pcb
	(version 20260206)
	(generator "pcbnew")
	(generator_version "10.0")
	(general
		(thickness 1.6)
		(legacy_teardrops no)
	)
	(paper "A4")
	(title_block
		(title "03242023_DA0F0TMBIJ0_F0T_Motherboard_J_brd_V01_OCP.brd")
		(comment 1 "Grand Teton / footprints 4137-4138 of 6105")
	)
	(layers
		(0 "F.Cu" signal "TOP")
		(4 "In1.Cu" signal "GND")
		(6 "In2.Cu" signal "IN1")
		(8 "In3.Cu" signal "GND1")
		(10 "In4.Cu" signal "IN2")
		(12 "In5.Cu" signal "GND2")
		(14 "In6.Cu" signal "IN3")
		(16 "In7.Cu" signal "GND3")
		(18 "In8.Cu" signal "VCC")
		(20 "In9.Cu" signal "VCC1")
		(22 "In10.Cu" signal "GND4")
		(24 "In11.Cu" signal "IN4")
		(26 "In12.Cu" signal "GND5")
		(28 "In13.Cu" signal "IN5")
		(30 "In14.Cu" signal "GND6")
		(32 "In15.Cu" signal "IN6")
		(34 "In16.Cu" signal "GND7")
		(2 "B.Cu" signal "BOTTOM")
		(9 "F.Adhes" user "F.Adhesive")
		(11 "B.Adhes" user "B.Adhesive")
		(13 "F.Paste" user "Package Geometry/Pastemask Top")
		(15 "B.Paste" user "Package Geometry/Pastemask Bottom")
		(5 "F.SilkS" user "Ref Des/Silkscreen Top")
		(7 "B.SilkS" user "Ref Des/Silkscreen Bottom")
		(1 "F.Mask" user "Board Geometry/Soldermask Top")
		(3 "B.Mask" user "Board Geometry/Soldermask Bottom")
		(17 "Dwgs.User" user "User.Drawings")
		(19 "Cmts.User" user "User.Comments")
		(21 "Eco1.User" user "User.Eco1")
		(23 "Eco2.User" user "User.Eco2")
		(25 "Edge.Cuts" user "Board Geometry/Outline")
		(27 "Margin" user)
		(31 "F.CrtYd" user "Package Geometry/Place Bound Top")
		(29 "B.CrtYd" user "Package Geometry/Place Bound Bottom")
		(35 "F.Fab" user "Ref Des/Assembly Top")
		(33 "B.Fab" user "Ref Des/Assembly Bottom")
	)
	(footprint ""
		(layer "F.Cu")
		(at 184.290208 -407.439622 90)
		(property "Reference" "PC2189"
			(at 0 0 90)
			(layer "F.SilkS")
			(hide yes)
			(effects
				(font
					(size 1.27 1.27)
				)
			)
		)
		(property "Value" ""
			(at 0 0 90)
			(layer "F.Fab")
			(effects
				(font
					(size 1.27 1.27)
				)
			)
		)
		(duplicate_pad_numbers_are_jumpers no)
		(fp_line
			(start 0.7874 -0.4064)
			(end 0.7874 0.4064)
			(stroke
				(width 0.1524)
				(type default)
			)
			(layer "F.SilkS")
		)
		(fp_line
			(start -0.7874 -0.4064)
			(end 0.7874 -0.4064)
			(stroke
				(width 0.1524)
				(type default)
			)
			(layer "F.SilkS")
		)
		(fp_line
			(start 0.7874 0.4064)
			(end -0.7874 0.4064)
			(stroke
				(width 0.1524)
				(type default)
			)
			(layer "F.SilkS")
		)
		(fp_line
			(start -0.7874 0.4064)
			(end -0.7874 -0.4064)
			(stroke
				(width 0.1524)
				(type default)
			)
			(layer "F.SilkS")
		)
		(fp_line
			(start -0.12065 -0.305054)
			(end -0.12065 -0.2794)
			(stroke
				(width 0.1)
				(type default)
			)
			(layer "F.Fab")
		)
		(fp_line
			(start -0.67945 -0.305054)
			(end -0.12065 -0.305054)
			(stroke
				(width 0.1)
				(type default)
			)
			(layer "F.Fab")
		)
		(fp_line
			(start 0.67945 -0.3048)
			(end 0.67945 0.3048)
			(stroke
				(width 0.1)
				(type default)
			)
			(layer "F.Fab")
		)
		(fp_line
			(start 0.12065 -0.3048)
			(end 0.67945 -0.3048)
			(stroke
				(width 0.1)
				(type default)
			)
			(layer "F.Fab")
		)
		(fp_line
			(start 0.12065 -0.2794)
			(end 0.12065 -0.3048)
			(stroke
				(width 0.1)
				(type default)
			)
			(layer "F.Fab")
		)
		(fp_line
			(start -0.12065 -0.2794)
			(end 0.12065 -0.2794)
			(stroke
				(width 0.1)
				(type default)
			)
			(layer "F.Fab")
		)
		(fp_line
			(start 0.120396 0.2794)
			(end -0.12065 0.2794)
			(stroke
				(width 0.1)
				(type default)
			)
			(layer "F.Fab")
		)
		(fp_line
			(start -0.12065 0.2794)
			(end -0.12065 0.3048)
			(stroke
				(width 0.1)
				(type default)
			)
			(layer "F.Fab")
		)
		(fp_line
			(start 0.67945 0.3048)
			(end 0.120396 0.3048)
			(stroke
				(width 0.1)
				(type default)
			)
			(layer "F.Fab")
		)
		(fp_line
			(start 0.120396 0.3048)
			(end 0.120396 0.2794)
			(stroke
				(width 0.1)
				(type default)
			)
			(layer "F.Fab")
		)
		(fp_line
			(start -0.12065 0.3048)
			(end -0.67945 0.3048)
			(stroke
				(width 0.1)
				(type default)
			)
			(layer "F.Fab")
		)
		(fp_line
			(start -0.67945 0.3048)
			(end -0.67945 -0.305054)
			(stroke
				(width 0.1)
				(type default)
			)
			(layer "F.Fab")
		)
		(pad "1" smd circle
			(at -0.40005 0 90)
			(size 0 0)
			(layers "F.Cu" "F.Mask" "F.Paste")
			(net "HSC_VSENSE")
		)
		(pad "2" smd circle
			(at 0.40005 0 90)
			(size 0 0)
			(layers "F.Cu" "F.Mask" "F.Paste")
			(net "AGND_HSC")
		)
	)
	(footprint ""
		(layer "F.Cu")
		(at 305.58994 -433.0573 90)
		(property "Reference" "R4135"
			(at 0 0 90)
			(layer "F.SilkS")
			(hide yes)
			(effects
				(font
					(size 1.27 1.27)
				)
			)
		)
		(property "Value" ""
			(at 0 0 90)
			(layer "F.Fab")
			(effects
				(font
					(size 1.27 1.27)
				)
			)
		)
		(duplicate_pad_numbers_are_jumpers no)
		(fp_line
			(start 0.7874 -0.4064)
			(end 0.7874 0.4064)
			(stroke
				(width 0.1524)
				(type default)
			)
			(layer "F.SilkS")
		)
		(fp_line
			(start -0.7874 -0.4064)
			(end 0.7874 -0.4064)
			(stroke
				(width 0.1524)
				(type default)
			)
			(layer "F.SilkS")
		)
		(fp_line
			(start 0.7874 0.4064)
			(end -0.7874 0.4064)
			(stroke
				(width 0.1524)
				(type default)
			)
			(layer "F.SilkS")
		)
		(fp_line
			(start -0.7874 0.4064)
			(end -0.7874 -0.4064)
			(stroke
				(width 0.1524)
				(type default)
			)
			(layer "F.SilkS")
		)
		(fp_line
			(start -0.12065 -0.305054)
			(end -0.12065 -0.2794)
			(stroke
				(width 0.1)
				(type default)
			)
			(layer "F.Fab")
		)
		(fp_line
			(start -0.67945 -0.305054)
			(end -0.12065 -0.305054)
			(stroke
				(width 0.1)
				(type default)
			)
			(layer "F.Fab")
		)
		(fp_line
			(start 0.67945 -0.3048)
			(end 0.67945 0.3048)
			(stroke
				(width 0.1)
				(type default)
			)
			(layer "F.Fab")
		)
		(fp_line
			(start 0.12065 -0.3048)
			(end 0.67945 -0.3048)
			(stroke
				(width 0.1)
				(type default)
			)
			(layer "F.Fab")
		)
		(fp_line
			(start 0.12065 -0.2794)
			(end 0.12065 -0.3048)
			(stroke
				(width 0.1)
				(type default)
			)
			(layer "F.Fab")
		)
		(fp_line
			(start -0.12065 -0.2794)
			(end 0.12065 -0.2794)
			(stroke
				(width 0.1)
				(type default)
			)
			(layer "F.Fab")
		)
		(fp_line
			(start 0.120396 0.2794)
			(end -0.12065 0.2794)
			(stroke
				(width 0.1)
				(type default)
			)
			(layer "F.Fab")
		)
		(fp_line
			(start -0.12065 0.2794)
			(end -0.12065 0.3048)
			(stroke
				(width 0.1)
				(type default)
			)
			(layer "F.Fab")
		)
		(fp_line
			(start 0.67945 0.3048)
			(end 0.120396 0.3048)
			(stroke
				(width 0.1)
				(type default)
			)
			(layer "F.Fab")
		)
		(fp_line
			(start 0.120396 0.3048)
			(end 0.120396 0.2794)
			(stroke
				(width 0.1)
				(type default)
			)
			(layer "F.Fab")
		)
		(fp_line
			(start -0.12065 0.3048)
			(end -0.67945 0.3048)
			(stroke
				(width 0.1)
				(type default)
			)
			(layer "F.Fab")
		)
		(fp_line
			(start -0.67945 0.3048)
			(end -0.67945 -0.305054)
			(stroke
				(width 0.1)
				(type default)
			)
			(layer "F.Fab")
		)
		(pad "1" smd circle
			(at -0.40005 0 90)
			(size 0 0)
			(layers "F.Cu" "F.Mask" "F.Paste")
			(net "P3V3_AUX")
		)
		(pad "2" smd circle
			(at 0.40005 0 90)
			(size 0 0)
			(layers "F.Cu" "F.Mask" "F.Paste")
			(net "PRSNT_CABLE_GPU_A2_N")
		)
	)
)
